(kicad_pcb
	(version 20260206)
	(generator "pcbnew")
	(generator_version "10.0")
	(general
		(thickness 1.6)
		(legacy_teardrops no)
	)
	(paper "A4")
	(title_block
		(title "01162023_DA0F0TEBIF0_F0T_Expander_BD_F_brd_V02_OCP.brd")
		(comment 1 "Grand Teton / footprints 7872-7882 of 9728")
	)
	(layers
		(0 "F.Cu" signal "TOP")
		(4 "In1.Cu" signal "GND")
		(6 "In2.Cu" signal "VCC")
		(8 "In3.Cu" signal "VCC1")
		(10 "In4.Cu" signal "GND1")
		(12 "In5.Cu" signal "IN1")
		(14 "In6.Cu" signal "GND2")
		(16 "In7.Cu" signal "IN2")
		(18 "In8.Cu" signal "GND3")
		(20 "In9.Cu" signal "IN3")
		(22 "In10.Cu" signal "GND4")
		(24 "In11.Cu" signal "IN4")
		(26 "In12.Cu" signal "GND5")
		(28 "In13.Cu" signal "IN5")
		(30 "In14.Cu" signal "GND6")
		(32 "In15.Cu" signal "IN6")
		(34 "In16.Cu" signal "GND7")
		(2 "B.Cu" signal "BOTTOM")
		(9 "F.Adhes" user "F.Adhesive")
		(11 "B.Adhes" user "B.Adhesive")
		(13 "F.Paste" user "Package Geometry/Pastemask Top")
		(15 "B.Paste" user "Package Geometry/Pastemask Bottom")
		(5 "F.SilkS" user "Ref Des/Silkscreen Top")
		(7 "B.SilkS" user "Ref Des/Silkscreen Bottom")
		(1 "F.Mask" user "Board Geometry/Soldermask Top")
		(3 "B.Mask" user "Board Geometry/Soldermask Bottom")
		(17 "Dwgs.User" user "User.Drawings")
		(19 "Cmts.User" user "User.Comments")
		(21 "Eco1.User" user "User.Eco1")
		(23 "Eco2.User" user "User.Eco2")
		(25 "Edge.Cuts" user "Board Geometry/Outline")
		(27 "Margin" user)
		(31 "F.CrtYd" user "Package Geometry/Place Bound Top")
		(29 "B.CrtYd" user "Package Geometry/Place Bound Bottom")
		(35 "F.Fab" user "Ref Des/Assembly Top")
		(33 "B.Fab" user "Ref Des/Assembly Bottom")
	)
	(footprint ""
		(layer "B.Cu")
		(at 327.523856 -224.955354)
		(property "Reference" "R6179"
			(at 0 0 0)
			(layer "B.SilkS")
			(hide yes)
			(effects
				(font
					(size 1.27 1.27)
				)
				(justify mirror)
			)
		)
		(property "Value" ""
			(at 0 0 0)
			(layer "B.Fab")
			(effects
				(font
					(size 1.27 1.27)
				)
				(justify mirror)
			)
		)
		(duplicate_pad_numbers_are_jumpers no)
		(fp_line
			(start -0.7874 -0.4064)
			(end -0.7874 0.4064)
			(stroke
				(width 0.1524)
				(type default)
			)
			(layer "B.SilkS")
		)
		(fp_line
			(start -0.7874 0.4064)
			(end 0.7874 0.4064)
			(stroke
				(width 0.1524)
				(type default)
			)
			(layer "B.SilkS")
		)
		(fp_line
			(start 0.7874 -0.4064)
			(end -0.7874 -0.4064)
			(stroke
				(width 0.1524)
				(type default)
			)
			(layer "B.SilkS")
		)
		(fp_line
			(start 0.7874 0.4064)
			(end 0.7874 -0.4064)
			(stroke
				(width 0.1524)
				(type default)
			)
			(layer "B.SilkS")
		)
		(fp_line
			(start -0.67945 -0.3048)
			(end -0.67945 0.3048)
			(stroke
				(width 0.1)
				(type default)
			)
			(layer "B.Fab")
		)
		(fp_line
			(start -0.67945 0.3048)
			(end -0.120396 0.3048)
			(stroke
				(width 0.1)
				(type default)
			)
			(layer "B.Fab")
		)
		(fp_line
			(start -0.12065 -0.3048)
			(end -0.67945 -0.3048)
			(stroke
				(width 0.1)
				(type default)
			)
			(layer "B.Fab")
		)
		(fp_line
			(start -0.12065 -0.2794)
			(end -0.12065 -0.3048)
			(stroke
				(width 0.1)
				(type default)
			)
			(layer "B.Fab")
		)
		(fp_line
			(start -0.120396 0.2794)
			(end 0.12065 0.2794)
			(stroke
				(width 0.1)
				(type default)
			)
			(layer "B.Fab")
		)
		(fp_line
			(start -0.120396 0.3048)
			(end -0.120396 0.2794)
			(stroke
				(width 0.1)
				(type default)
			)
			(layer "B.Fab")
		)
		(fp_line
			(start 0.12065 -0.305054)
			(end 0.12065 -0.2794)
			(stroke
				(width 0.1)
				(type default)
			)
			(layer "B.Fab")
		)
		(fp_line
			(start 0.12065 -0.2794)
			(end -0.12065 -0.2794)
			(stroke
				(width 0.1)
				(type default)
			)
			(layer "B.Fab")
		)
		(fp_line
			(start 0.12065 0.2794)
			(end 0.12065 0.3048)
			(stroke
				(width 0.1)
				(type default)
			)
			(layer "B.Fab")
		)
		(fp_line
			(start 0.12065 0.3048)
			(end 0.67945 0.3048)
			(stroke
				(width 0.1)
				(type default)
			)
			(layer "B.Fab")
		)
		(fp_line
			(start 0.67945 -0.305054)
			(end 0.12065 -0.305054)
			(stroke
				(width 0.1)
				(type default)
			)
			(layer "B.Fab")
		)
		(fp_line
			(start 0.67945 0.3048)
			(end 0.67945 -0.305054)
			(stroke
				(width 0.1)
				(type default)
			)
			(layer "B.Fab")
		)
		(pad "1" smd circle
			(at 0.40005 0 180)
			(size 0 0)
			(layers "B.Cu" "B.Mask" "B.Paste")
			(net "PWR_EN_P3V3_R")
		)
		(pad "2" smd circle
			(at -0.40005 0 180)
			(size 0 0)
			(layers "B.Cu" "B.Mask" "B.Paste")
			(net "GND")
		)
	)
	(footprint ""
		(layer "B.Cu")
		(at 285.199836 -303.499774 -90)
		(property "Reference" "C3260"
			(at 0 0 90)
			(layer "B.SilkS")
			(hide yes)
			(effects
				(font
					(size 1.27 1.27)
				)
				(justify mirror)
			)
		)
		(property "Value" ""
			(at 0 0 90)
			(layer "B.Fab")
			(effects
				(font
					(size 1.27 1.27)
				)
				(justify mirror)
			)
		)
		(duplicate_pad_numbers_are_jumpers no)
		(fp_line
			(start -0.299974 0.150114)
			(end 0.299974 0.150114)
			(stroke
				(width 0.1)
				(type default)
			)
			(layer "B.Fab")
		)
		(fp_line
			(start 0.299974 0.150114)
			(end 0.299974 -0.150114)
			(stroke
				(width 0.1)
				(type default)
			)
			(layer "B.Fab")
		)
		(fp_line
			(start -0.299974 -0.150114)
			(end -0.299974 0.150114)
			(stroke
				(width 0.1)
				(type default)
			)
			(layer "B.Fab")
		)
		(fp_line
			(start 0.299974 -0.150114)
			(end -0.299974 -0.150114)
			(stroke
				(width 0.1)
				(type default)
			)
			(layer "B.Fab")
		)
		(pad "1" smd rect
			(at 0.2667 0 90)
			(size 0.3048 0.381)
			(layers "B.Cu" "B.Mask" "B.Paste")
			(net "P1V25_PEX2")
		)
		(pad "2" smd rect
			(at -0.2667 0 90)
			(size 0.3048 0.381)
			(layers "B.Cu" "B.Mask" "B.Paste")
			(net "GND")
		)
	)
	(footprint ""
		(layer "B.Cu")
		(at 284.724856 -293.99992 90)
		(property "Reference" "C1625"
			(at 0 0 90)
			(layer "B.SilkS")
			(hide yes)
			(effects
				(font
					(size 1.27 1.27)
				)
				(justify mirror)
			)
		)
		(property "Value" ""
			(at 0 0 90)
			(layer "B.Fab")
			(effects
				(font
					(size 1.27 1.27)
				)
				(justify mirror)
			)
		)
		(duplicate_pad_numbers_are_jumpers no)
		(fp_line
			(start 0.299974 -0.150114)
			(end -0.299974 -0.150114)
			(stroke
				(width 0.1)
				(type default)
			)
			(layer "B.Fab")
		)
		(fp_line
			(start -0.299974 -0.150114)
			(end -0.299974 0.150114)
			(stroke
				(width 0.1)
				(type default)
			)
			(layer "B.Fab")
		)
		(fp_line
			(start 0.299974 0.150114)
			(end 0.299974 -0.150114)
			(stroke
				(width 0.1)
				(type default)
			)
			(layer "B.Fab")
		)
		(fp_line
			(start -0.299974 0.150114)
			(end 0.299974 0.150114)
			(stroke
				(width 0.1)
				(type default)
			)
			(layer "B.Fab")
		)
		(pad "1" smd rect
			(at 0.2667 0 270)
			(size 0.3048 0.381)
			(layers "B.Cu" "B.Mask" "B.Paste")
			(net "P0V8_PEX2")
		)
		(pad "2" smd rect
			(at -0.2667 0 270)
			(size 0.3048 0.381)
			(layers "B.Cu" "B.Mask" "B.Paste")
			(net "GND")
		)
	)
	(footprint ""
		(layer "B.Cu")
		(at 189.500002 -112.604296)
		(property "Reference" "C895"
			(at 0 0 0)
			(layer "B.SilkS")
			(hide yes)
			(effects
				(font
					(size 1.27 1.27)
				)
				(justify mirror)
			)
		)
		(property "Value" ""
			(at 0 0 0)
			(layer "B.Fab")
			(effects
				(font
					(size 1.27 1.27)
				)
				(justify mirror)
			)
		)
		(duplicate_pad_numbers_are_jumpers no)
		(fp_line
			(start -0.299974 -0.150114)
			(end -0.299974 0.150114)
			(stroke
				(width 0.1)
				(type default)
			)
			(layer "B.Fab")
		)
		(fp_line
			(start -0.299974 0.150114)
			(end 0.299974 0.150114)
			(stroke
				(width 0.1)
				(type default)
			)
			(layer "B.Fab")
		)
		(fp_line
			(start 0.299974 -0.150114)
			(end -0.299974 -0.150114)
			(stroke
				(width 0.1)
				(type default)
			)
			(layer "B.Fab")
		)
		(fp_line
			(start 0.299974 0.150114)
			(end 0.299974 -0.150114)
			(stroke
				(width 0.1)
				(type default)
			)
			(layer "B.Fab")
		)
		(pad "1" smd rect
			(at 0.2667 0 180)
			(size 0.3048 0.381)
			(layers "B.Cu" "B.Mask" "B.Paste")
			(net "P12V_NIC3")
		)
		(pad "2" smd rect
			(at -0.2667 0 180)
			(size 0.3048 0.381)
			(layers "B.Cu" "B.Mask" "B.Paste")
			(net "GND")
		)
	)
	(footprint ""
		(layer "B.Cu")
		(at 67.249802 -301.599854 -90)
		(property "Reference" "C1171"
			(at 0 0 90)
			(layer "B.SilkS")
			(hide yes)
			(effects
				(font
					(size 1.27 1.27)
				)
				(justify mirror)
			)
		)
		(property "Value" ""
			(at 0 0 90)
			(layer "B.Fab")
			(effects
				(font
					(size 1.27 1.27)
				)
				(justify mirror)
			)
		)
		(duplicate_pad_numbers_are_jumpers no)
		(fp_line
			(start -0.299974 0.150114)
			(end 0.299974 0.150114)
			(stroke
				(width 0.1)
				(type default)
			)
			(layer "B.Fab")
		)
		(fp_line
			(start 0.299974 0.150114)
			(end 0.299974 -0.150114)
			(stroke
				(width 0.1)
				(type default)
			)
			(layer "B.Fab")
		)
		(fp_line
			(start -0.299974 -0.150114)
			(end -0.299974 0.150114)
			(stroke
				(width 0.1)
				(type default)
			)
			(layer "B.Fab")
		)
		(fp_line
			(start 0.299974 -0.150114)
			(end -0.299974 -0.150114)
			(stroke
				(width 0.1)
				(type default)
			)
			(layer "B.Fab")
		)
		(pad "1" smd rect
			(at 0.2667 0 90)
			(size 0.3048 0.381)
			(layers "B.Cu" "B.Mask" "B.Paste")
			(net "P0V8_SERDES_VDDA_PEX0")
		)
		(pad "2" smd rect
			(at -0.2667 0 90)
			(size 0.3048 0.381)
			(layers "B.Cu" "B.Mask" "B.Paste")
			(net "GND")
		)
	)
	(footprint ""
		(layer "B.Cu")
		(at 162.4457 -295.275)
		(property "Reference" "C3217"
			(at 0 0 0)
			(layer "B.SilkS")
			(hide yes)
			(effects
				(font
					(size 1.27 1.27)
				)
				(justify mirror)
			)
		)
		(property "Value" ""
			(at 0 0 0)
			(layer "B.Fab")
			(effects
				(font
					(size 1.27 1.27)
				)
				(justify mirror)
			)
		)
		(duplicate_pad_numbers_are_jumpers no)
		(fp_line
			(start -0.299974 -0.150114)
			(end -0.299974 0.150114)
			(stroke
				(width 0.1)
				(type default)
			)
			(layer "B.Fab")
		)
		(fp_line
			(start -0.299974 0.150114)
			(end 0.299974 0.150114)
			(stroke
				(width 0.1)
				(type default)
			)
			(layer "B.Fab")
		)
		(fp_line
			(start 0.299974 -0.150114)
			(end -0.299974 -0.150114)
			(stroke
				(width 0.1)
				(type default)
			)
			(layer "B.Fab")
		)
		(fp_line
			(start 0.299974 0.150114)
			(end 0.299974 -0.150114)
			(stroke
				(width 0.1)
				(type default)
			)
			(layer "B.Fab")
		)
		(pad "1" smd rect
			(at 0.2667 0 180)
			(size 0.3048 0.381)
			(layers "B.Cu" "B.Mask" "B.Paste")
			(net "PCEPLL4_VDDA18_PEX1")
		)
		(pad "2" smd rect
			(at -0.2667 0 180)
			(size 0.3048 0.381)
			(layers "B.Cu" "B.Mask" "B.Paste")
			(net "GND")
		)
	)
	(footprint ""
		(layer "B.Cu")
		(at 341.293704 -220.38691 90)
		(property "Reference" "C2067"
			(at 0 0 90)
			(layer "B.SilkS")
			(hide yes)
			(effects
				(font
					(size 1.27 1.27)
				)
				(justify mirror)
			)
		)
		(property "Value" ""
			(at 0 0 90)
			(layer "B.Fab")
			(effects
				(font
					(size 1.27 1.27)
				)
				(justify mirror)
			)
		)
		(duplicate_pad_numbers_are_jumpers no)
		(fp_line
			(start 0.69215 -0.2921)
			(end -0.69215 -0.2921)
			(stroke
				(width 0.1524)
				(type default)
			)
			(layer "B.SilkS")
		)
		(fp_line
			(start -0.69215 -0.2921)
			(end -0.69215 0.2921)
			(stroke
				(width 0.1524)
				(type default)
			)
			(layer "B.SilkS")
		)
		(fp_line
			(start 0.69215 0.2921)
			(end 0.69215 -0.2921)
			(stroke
				(width 0.1524)
				(type default)
			)
			(layer "B.SilkS")
		)
		(fp_line
			(start -0.69215 0.2921)
			(end 0.69215 0.2921)
			(stroke
				(width 0.1524)
				(type default)
			)
			(layer "B.SilkS")
		)
		(fp_line
			(start 0.51435 -0.2794)
			(end -0.51435 -0.2794)
			(stroke
				(width 0.1)
				(type default)
			)
			(layer "B.Fab")
		)
		(fp_line
			(start -0.51435 -0.2794)
			(end -0.51435 0.2794)
			(stroke
				(width 0.1)
				(type default)
			)
			(layer "B.Fab")
		)
		(fp_line
			(start 0.51435 0.2794)
			(end 0.51435 -0.2794)
			(stroke
				(width 0.1)
				(type default)
			)
			(layer "B.Fab")
		)
		(fp_line
			(start -0.51435 0.2794)
			(end 0.51435 0.2794)
			(stroke
				(width 0.1)
				(type default)
			)
			(layer "B.Fab")
		)
		(pad "1" smd circle
			(at 0.40005 0 270)
			(size 0 0)
			(layers "B.Cu" "B.Mask" "B.Paste")
			(net "P3V3_VCC_FPGA_CORE")
		)
		(pad "2" smd circle
			(at -0.40005 0 270)
			(size 0 0)
			(layers "B.Cu" "B.Mask" "B.Paste")
			(net "GND")
		)
		(zone
			(layer "B.Cu")
			(hatch none 0.5)
			(connect_pads
				(clearance 0)
			)
			(min_thickness 0.25)
			(keepout
				(tracks not_allowed)
				(vias allowed)
				(pads allowed)
				(copperpour not_allowed)
				(footprints allowed)
			)
			(placement
				(enabled no)
				(sheetname "")
			)
			(fill
				(thermal_gap 0.5)
				(thermal_bridge_width 0.5)
				(island_removal_mode 0)
			)
			(polygon
				(pts
					(xy 341.381334 -220.57741) (xy 341.4395 -220.48597) (xy 341.4395 -220.28658) (xy 341.381334 -220.19641)
					(xy 341.206074 -220.19641) (xy 341.147654 -220.28658) (xy 341.147654 -220.48597) (xy 341.20582 -220.57741)
				)
			)
		)
	)
	(footprint ""
		(layer "B.Cu")
		(at 169.099992 -292.099746 90)
		(property "Reference" "C1435"
			(at 0 0 90)
			(layer "B.SilkS")
			(hide yes)
			(effects
				(font
					(size 1.27 1.27)
				)
				(justify mirror)
			)
		)
		(property "Value" ""
			(at 0 0 90)
			(layer "B.Fab")
			(effects
				(font
					(size 1.27 1.27)
				)
				(justify mirror)
			)
		)
		(duplicate_pad_numbers_are_jumpers no)
		(fp_line
			(start 0.299974 -0.150114)
			(end -0.299974 -0.150114)
			(stroke
				(width 0.1)
				(type default)
			)
			(layer "B.Fab")
		)
		(fp_line
			(start -0.299974 -0.150114)
			(end -0.299974 0.150114)
			(stroke
				(width 0.1)
				(type default)
			)
			(layer "B.Fab")
		)
		(fp_line
			(start 0.299974 0.150114)
			(end 0.299974 -0.150114)
			(stroke
				(width 0.1)
				(type default)
			)
			(layer "B.Fab")
		)
		(fp_line
			(start -0.299974 0.150114)
			(end 0.299974 0.150114)
			(stroke
				(width 0.1)
				(type default)
			)
			(layer "B.Fab")
		)
		(pad "1" smd rect
			(at 0.2667 0 270)
			(size 0.3048 0.381)
			(layers "B.Cu" "B.Mask" "B.Paste")
			(net "P0V8_SERDES_VDDA_PEX1")
		)
		(pad "2" smd rect
			(at -0.2667 0 270)
			(size 0.3048 0.381)
			(layers "B.Cu" "B.Mask" "B.Paste")
			(net "GND")
		)
	)
	(footprint ""
		(layer "B.Cu")
		(at 58.699908 -301.599854 -90)
		(property "Reference" "C1181"
			(at 0 0 90)
			(layer "B.SilkS")
			(hide yes)
			(effects
				(font
					(size 1.27 1.27)
				)
				(justify mirror)
			)
		)
		(property "Value" ""
			(at 0 0 90)
			(layer "B.Fab")
			(effects
				(font
					(size 1.27 1.27)
				)
				(justify mirror)
			)
		)
		(duplicate_pad_numbers_are_jumpers no)
		(fp_line
			(start -0.299974 0.150114)
			(end 0.299974 0.150114)
			(stroke
				(width 0.1)
				(type default)
			)
			(layer "B.Fab")
		)
		(fp_line
			(start 0.299974 0.150114)
			(end 0.299974 -0.150114)
			(stroke
				(width 0.1)
				(type default)
			)
			(layer "B.Fab")
		)
		(fp_line
			(start -0.299974 -0.150114)
			(end -0.299974 0.150114)
			(stroke
				(width 0.1)
				(type default)
			)
			(layer "B.Fab")
		)
		(fp_line
			(start 0.299974 -0.150114)
			(end -0.299974 -0.150114)
			(stroke
				(width 0.1)
				(type default)
			)
			(layer "B.Fab")
		)
		(pad "1" smd rect
			(at 0.2667 0 90)
			(size 0.3048 0.381)
			(layers "B.Cu" "B.Mask" "B.Paste")
			(net "P0V8_SERDES_VDDA_PEX0")
		)
		(pad "2" smd rect
			(at -0.2667 0 90)
			(size 0.3048 0.381)
			(layers "B.Cu" "B.Mask" "B.Paste")
			(net "GND")
		)
	)
	(footprint ""
		(layer "B.Cu")
		(at 225.530664 -204.44206 90)
		(property "Reference" "R5475"
			(at 0 0 90)
			(layer "B.SilkS")
			(hide yes)
			(effects
				(font
					(size 1.27 1.27)
				)
				(justify mirror)
			)
		)
		(property "Value" ""
			(at 0 0 90)
			(layer "B.Fab")
			(effects
				(font
					(size 1.27 1.27)
				)
				(justify mirror)
			)
		)
		(duplicate_pad_numbers_are_jumpers no)
		(fp_line
			(start 0.7874 -0.4064)
			(end -0.7874 -0.4064)
			(stroke
				(width 0.1524)
				(type default)
			)
			(layer "B.SilkS")
		)
		(fp_line
			(start -0.7874 -0.4064)
			(end -0.7874 0.4064)
			(stroke
				(width 0.1524)
				(type default)
			)
			(layer "B.SilkS")
		)
		(fp_line
			(start 0.7874 0.4064)
			(end 0.7874 -0.4064)
			(stroke
				(width 0.1524)
				(type default)
			)
			(layer "B.SilkS")
		)
		(fp_line
			(start -0.7874 0.4064)
			(end 0.7874 0.4064)
			(stroke
				(width 0.1524)
				(type default)
			)
			(layer "B.SilkS")
		)
		(fp_line
			(start 0.67945 -0.305054)
			(end 0.12065 -0.305054)
			(stroke
				(width 0.1)
				(type default)
			)
			(layer "B.Fab")
		)
		(fp_line
			(start 0.12065 -0.305054)
			(end 0.12065 -0.2794)
			(stroke
				(width 0.1)
				(type default)
			)
			(layer "B.Fab")
		)
		(fp_line
			(start -0.12065 -0.3048)
			(end -0.67945 -0.3048)
			(stroke
				(width 0.1)
				(type default)
			)
			(layer "B.Fab")
		)
		(fp_line
			(start -0.67945 -0.3048)
			(end -0.67945 0.3048)
			(stroke
				(width 0.1)
				(type default)
			)
			(layer "B.Fab")
		)
		(fp_line
			(start 0.12065 -0.2794)
			(end -0.12065 -0.2794)
			(stroke
				(width 0.1)
				(type default)
			)
			(layer "B.Fab")
		)
		(fp_line
			(start -0.12065 -0.2794)
			(end -0.12065 -0.3048)
			(stroke
				(width 0.1)
				(type default)
			)
			(layer "B.Fab")
		)
		(fp_line
			(start 0.12065 0.2794)
			(end 0.12065 0.3048)
			(stroke
				(width 0.1)
				(type default)
			)
			(layer "B.Fab")
		)
		(fp_line
			(start -0.120396 0.2794)
			(end 0.12065 0.2794)
			(stroke
				(width 0.1)
				(type default)
			)
			(layer "B.Fab")
		)
		(fp_line
			(start 0.67945 0.3048)
			(end 0.67945 -0.305054)
			(stroke
				(width 0.1)
				(type default)
			)
			(layer "B.Fab")
		)
		(fp_line
			(start 0.12065 0.3048)
			(end 0.67945 0.3048)
			(stroke
				(width 0.1)
				(type default)
			)
			(layer "B.Fab")
		)
		(fp_line
			(start -0.120396 0.3048)
			(end -0.120396 0.2794)
			(stroke
				(width 0.1)
				(type default)
			)
			(layer "B.Fab")
		)
		(fp_line
			(start -0.67945 0.3048)
			(end -0.120396 0.3048)
			(stroke
				(width 0.1)
				(type default)
			)
			(layer "B.Fab")
		)
		(pad "1" smd circle
			(at 0.40005 0 270)
			(size 0 0)
			(layers "B.Cu" "B.Mask" "B.Paste")
			(net "RST_SMB_FIO_R_N")
		)
		(pad "2" smd circle
			(at -0.40005 0 270)
			(size 0 0)
			(layers "B.Cu" "B.Mask" "B.Paste")
			(net "P3V3_AUX")
		)
	)
	(footprint ""
		(layer "B.Cu")
		(at 421.700198 -111.791496)
		(property "Reference" "C952"
			(at 0 0 0)
			(layer "B.SilkS")
			(hide yes)
			(effects
				(font
					(size 1.27 1.27)
				)
				(justify mirror)
			)
		)
		(property "Value" ""
			(at 0 0 0)
			(layer "B.Fab")
			(effects
				(font
					(size 1.27 1.27)
				)
				(justify mirror)
			)
		)
		(duplicate_pad_numbers_are_jumpers no)
		(fp_line
			(start -0.299974 -0.150114)
			(end -0.299974 0.150114)
			(stroke
				(width 0.1)
				(type default)
			)
			(layer "B.Fab")
		)
		(fp_line
			(start -0.299974 0.150114)
			(end 0.299974 0.150114)
			(stroke
				(width 0.1)
				(type default)
			)
			(layer "B.Fab")
		)
		(fp_line
			(start 0.299974 -0.150114)
			(end -0.299974 -0.150114)
			(stroke
				(width 0.1)
				(type default)
			)
			(layer "B.Fab")
		)
		(fp_line
			(start 0.299974 0.150114)
			(end 0.299974 -0.150114)
			(stroke
				(width 0.1)
				(type default)
			)
			(layer "B.Fab")
		)
		(pad "1" smd rect
			(at 0.2667 0 180)
			(size 0.3048 0.381)
			(layers "B.Cu" "B.Mask" "B.Paste")
			(net "P12V_NIC7")
		)
		(pad "2" smd rect
			(at -0.2667 0 180)
			(size 0.3048 0.381)
			(layers "B.Cu" "B.Mask" "B.Paste")
			(net "GND")
		)
	)
)
